# T6G (Grand Teton) — schematic netlist excerpt (pin names and nets, part order shuffled) for the footprints in the layout excerpt that follows; sources: Cadence DE-HDL packaged netlist, KiCad conversion of 04192023_DAF0TMB3IC0_F0TG_MB_C_brd_V02_OCP.brd

U153  SN74AUC2G66DCTR  IC  pkg SSOP8  page 174
  \1a\  = JTAG_CPUX_TDI
  \1b\  = JTAG_CPU0_R_TDI
  \2c\  = FM_PLD_CPU0_PRSNT_HDT_N
  GND  = GND
  \2a\  = JTAG_CPUX_TDI
  \2b\  = JTAG_CPU0_BYPASS
  \1c\  = CPU0_HDT_BYPASS_SEL
  VCC  = PVDD18_S5_P0

R3708  Q_RES  10K 1% EMPTY  pkg 0402LF  page 252 : A = P3V3_AUX ; B = PCA9548_PCIE0_ADDR0

(kicad_pcb
	(version 20260206)
	(generator "pcbnew")
	(generator_version "10.0")
	(general
		(thickness 1.6)
		(legacy_teardrops no)
	)
	(paper "A4")
	(title_block
		(title "04192023_DAF0TMB3IC0_F0TG_MB_C_brd_V02_OCP.brd")
		(comment 1 "Grand Teton / footprints 4846-4847 of 8354")
	)
	(layers
		(0 "F.Cu" signal "TOP")
		(4 "In1.Cu" signal "GND")
		(6 "In2.Cu" signal "IN1")
		(8 "In3.Cu" signal "GND1")
		(10 "In4.Cu" signal "IN2")
		(12 "In5.Cu" signal "GND2")
		(14 "In6.Cu" signal "IN3")
		(16 "In7.Cu" signal "GND3")
		(18 "In8.Cu" signal "VCC")
		(20 "In9.Cu" signal "VCC1")
		(22 "In10.Cu" signal "GND4")
		(24 "In11.Cu" signal "IN4")
		(26 "In12.Cu" signal "GND5")
		(28 "In13.Cu" signal "IN5")
		(30 "In14.Cu" signal "GND6")
		(32 "In15.Cu" signal "IN6")
		(34 "In16.Cu" signal "GND7")
		(2 "B.Cu" signal "BOTTOM")
		(9 "F.Adhes" user "F.Adhesive")
		(11 "B.Adhes" user "B.Adhesive")
		(13 "F.Paste" user "Package Geometry/Pastemask Top")
		(15 "B.Paste" user "Package Geometry/Pastemask Bottom")
		(5 "F.SilkS" user "Ref Des/Silkscreen Top")
		(7 "B.SilkS" user "Ref Des/Silkscreen Bottom")
		(1 "F.Mask" user "Board Geometry/Soldermask Top")
		(3 "B.Mask" user "Board Geometry/Soldermask Bottom")
		(17 "Dwgs.User" user "User.Drawings")
		(19 "Cmts.User" user "User.Comments")
		(21 "Eco1.User" user "User.Eco1")
		(23 "Eco2.User" user "User.Eco2")
		(25 "Edge.Cuts" user "Board Geometry/Outline")
		(27 "Margin" user)
		(31 "F.CrtYd" user "Package Geometry/Place Bound Top")
		(29 "B.CrtYd" user "Package Geometry/Place Bound Bottom")
		(35 "F.Fab" user "Ref Des/Assembly Top")
		(33 "B.Fab" user "Ref Des/Assembly Bottom")
	)
	(footprint ""
		(layer "F.Cu")
		(at 254.592836 -126.91745)
		(property "Reference" "R3708"
			(at 0 0 0)
			(layer "F.SilkS")
			(hide yes)
			(effects
				(font
					(size 1.27 1.27)
				)
			)
		)
		(property "Value" ""
			(at 0 0 0)
			(layer "F.Fab")
			(effects
				(font
					(size 1.27 1.27)
				)
			)
		)
		(duplicate_pad_numbers_are_jumpers no)
		(fp_line
			(start -0.7874 -0.4064)
			(end 0.7874 -0.4064)
			(stroke
				(width 0.1524)
				(type default)
			)
			(layer "F.SilkS")
		)
		(fp_line
			(start -0.7874 0.4064)
			(end -0.7874 -0.4064)
			(stroke
				(width 0.1524)
				(type default)
			)
			(layer "F.SilkS")
		)
		(fp_line
			(start 0.7874 -0.4064)
			(end 0.7874 0.4064)
			(stroke
				(width 0.1524)
				(type default)
			)
			(layer "F.SilkS")
		)
		(fp_line
			(start 0.7874 0.4064)
			(end -0.7874 0.4064)
			(stroke
				(width 0.1524)
				(type default)
			)
			(layer "F.SilkS")
		)
		(fp_line
			(start -0.67945 -0.305054)
			(end -0.12065 -0.305054)
			(stroke
				(width 0.1)
				(type default)
			)
			(layer "F.Fab")
		)
		(fp_line
			(start -0.67945 0.3048)
			(end -0.67945 -0.305054)
			(stroke
				(width 0.1)
				(type default)
			)
			(layer "F.Fab")
		)
		(fp_line
			(start -0.12065 -0.305054)
			(end -0.12065 -0.2794)
			(stroke
				(width 0.1)
				(type default)
			)
			(layer "F.Fab")
		)
		(fp_line
			(start -0.12065 -0.2794)
			(end 0.12065 -0.2794)
			(stroke
				(width 0.1)
				(type default)
			)
			(layer "F.Fab")
		)
		(fp_line
			(start -0.12065 0.2794)
			(end -0.12065 0.3048)
			(stroke
				(width 0.1)
				(type default)
			)
			(layer "F.Fab")
		)
		(fp_line
			(start -0.12065 0.3048)
			(end -0.67945 0.3048)
			(stroke
				(width 0.1)
				(type default)
			)
			(layer "F.Fab")
		)
		(fp_line
			(start 0.120396 0.2794)
			(end -0.12065 0.2794)
			(stroke
				(width 0.1)
				(type default)
			)
			(layer "F.Fab")
		)
		(fp_line
			(start 0.120396 0.3048)
			(end 0.120396 0.2794)
			(stroke
				(width 0.1)
				(type default)
			)
			(layer "F.Fab")
		)
		(fp_line
			(start 0.12065 -0.3048)
			(end 0.67945 -0.3048)
			(stroke
				(width 0.1)
				(type default)
			)
			(layer "F.Fab")
		)
		(fp_line
			(start 0.12065 -0.2794)
			(end 0.12065 -0.3048)
			(stroke
				(width 0.1)
				(type default)
			)
			(layer "F.Fab")
		)
		(fp_line
			(start 0.67945 -0.3048)
			(end 0.67945 0.3048)
			(stroke
				(width 0.1)
				(type default)
			)
			(layer "F.Fab")
		)
		(fp_line
			(start 0.67945 0.3048)
			(end 0.120396 0.3048)
			(stroke
				(width 0.1)
				(type default)
			)
			(layer "F.Fab")
		)
		(pad "1" smd circle
			(at -0.40005 0)
			(size 0 0)
			(layers "F.Cu" "F.Mask" "F.Paste")
			(net "P3V3_AUX")
		)
		(pad "2" smd circle
			(at 0.40005 0)
			(size 0 0)
			(layers "F.Cu" "F.Mask" "F.Paste")
			(net "PCA9548_PCIE0_ADDR0")
		)
	)
	(footprint ""
		(layer "F.Cu")
		(at 234.739688 -148.948648 180)
		(property "Reference" "U153"
			(at -3.725164 -3.332988 0)
			(unlocked yes)
			(layer "F.SilkS")
			(effects
				(font
					(size 0.7874 0.5842)
					(thickness 0.1524)
				)
				(justify left)
			)
		)
		(property "Value" ""
			(at 0 0 180)
			(layer "F.Fab")
			(effects
				(font
					(size 1.27 1.27)
				)
			)
		)
		(duplicate_pad_numbers_are_jumpers no)
		(fp_line
			(start 1.0414 1.575054)
			(end -1.0414 1.575054)
			(stroke
				(width 0.1524)
				(type default)
			)
			(layer "F.SilkS")
		)
		(fp_line
			(start 1.0414 -1.575054)
			(end 1.0414 1.575054)
			(stroke
				(width 0.1524)
				(type default)
			)
			(layer "F.SilkS")
		)
		(fp_line
			(start 0.254 -1.575054)
			(end 1.0414 -1.575054)
			(stroke
				(width 0.1524)
				(type default)
			)
			(layer "F.SilkS")
		)
		(fp_line
			(start 0.2286 -1.575054)
			(end 0 -1.272032)
			(stroke
				(width 0.1524)
				(type default)
			)
			(layer "F.SilkS")
		)
		(fp_line
			(start 0 -1.272032)
			(end -0.254 -1.575054)
			(stroke
				(width 0.1524)
				(type default)
			)
			(layer "F.SilkS")
		)
		(fp_line
			(start -1.0414 1.575054)
			(end -1.0414 -1.575054)
			(stroke
				(width 0.1524)
				(type default)
			)
			(layer "F.SilkS")
		)
		(fp_line
			(start -1.0414 -1.575054)
			(end -0.254 -1.575054)
			(stroke
				(width 0.1524)
				(type default)
			)
			(layer "F.SilkS")
		)
		(fp_poly
			(pts
				(xy -3.960876 -2.091182) (xy -3.242564 -2.809748) (xy -2.883154 -1.732026)
			)
			(stroke
				(width 0)
				(type default)
			)
			(fill yes)
			(layer "F.SilkS")
		)
		(fp_line
			(start 2.5654 1.2192)
			(end 1.4478 1.2192)
			(stroke
				(width 0.1)
				(type default)
			)
			(layer "F.Fab")
		)
		(fp_line
			(start 2.5654 -1.2192)
			(end 2.5654 1.2192)
			(stroke
				(width 0.1)
				(type default)
			)
			(layer "F.Fab")
		)
		(fp_line
			(start 1.4478 1.5748)
			(end -1.4478 1.5748)
			(stroke
				(width 0.1)
				(type default)
			)
			(layer "F.Fab")
		)
		(fp_line
			(start 1.4478 1.2192)
			(end 1.4478 1.5748)
			(stroke
				(width 0.1)
				(type default)
			)
			(layer "F.Fab")
		)
		(fp_line
			(start 1.4478 -1.2192)
			(end 2.5654 -1.2192)
			(stroke
				(width 0.1)
				(type default)
			)
			(layer "F.Fab")
		)
		(fp_line
			(start 1.4478 -1.5748)
			(end 1.4478 -1.2192)
			(stroke
				(width 0.1)
				(type default)
			)
			(layer "F.Fab")
		)
		(fp_line
			(start -1.4478 1.5748)
			(end -1.4478 1.2192)
			(stroke
				(width 0.1)
				(type default)
			)
			(layer "F.Fab")
		)
		(fp_line
			(start -1.4478 1.2192)
			(end -2.5654 1.2192)
			(stroke
				(width 0.1)
				(type default)
			)
			(layer "F.Fab")
		)
		(fp_line
			(start -1.4478 -1.2192)
			(end -1.4478 -1.5748)
			(stroke
				(width 0.1)
				(type default)
			)
			(layer "F.Fab")
		)
		(fp_line
			(start -1.4478 -1.5748)
			(end 1.4478 -1.5748)
			(stroke
				(width 0.1)
				(type default)
			)
			(layer "F.Fab")
		)
		(fp_line
			(start -2.5654 1.2192)
			(end -2.5654 -1.2192)
			(stroke
				(width 0.1)
				(type default)
			)
			(layer "F.Fab")
		)
		(fp_line
			(start -2.5654 -1.2192)
			(end -1.4478 -1.2192)
			(stroke
				(width 0.1)
				(type default)
			)
			(layer "F.Fab")
		)
		(fp_poly
			(pts
				(xy -2.710688 -0.975106) (xy -3.726688 -1.483106) (xy -3.726688 -0.467106)
			)
			(stroke
				(width 0)
				(type default)
			)
			(fill yes)
			(layer "F.Fab")
		)
		(pad "1" smd rect
			(at -1.849882 -0.975106 90)
			(size 0.3556 1.3208)
			(layers "F.Cu" "F.Mask" "F.Paste")
			(net "JTAG_CPUX_TDI")
		)
		(pad "2" smd rect
			(at -1.849882 -0.32512 90)
			(size 0.3556 1.3208)
			(layers "F.Cu" "F.Mask" "F.Paste")
			(net "JTAG_CPU0_R_TDI")
		)
		(pad "3" smd rect
			(at -1.849882 0.32512 90)
			(size 0.3556 1.3208)
			(layers "F.Cu" "F.Mask" "F.Paste")
			(net "FM_PLD_CPU0_PRSNT_HDT_N")
		)
		(pad "4" smd rect
			(at -1.849882 0.975106 90)
			(size 0.3556 1.3208)
			(layers "F.Cu" "F.Mask" "F.Paste")
			(net "GND")
		)
		(pad "5" smd rect
			(at 1.849882 0.975106 90)
			(size 0.3556 1.3208)
			(layers "F.Cu" "F.Mask" "F.Paste")
			(net "JTAG_CPUX_TDI")
		)
		(pad "6" smd rect
			(at 1.849882 0.32512 90)
			(size 0.3556 1.3208)
			(layers "F.Cu" "F.Mask" "F.Paste")
			(net "JTAG_CPU0_BYPASS")
		)
		(pad "7" smd rect
			(at 1.849882 -0.32512 90)
			(size 0.3556 1.3208)
			(layers "F.Cu" "F.Mask" "F.Paste")
			(net "CPU0_HDT_BYPASS_SEL")
		)
		(pad "8" smd rect
			(at 1.849882 -0.975106 90)
			(size 0.3556 1.3208)
			(layers "F.Cu" "F.Mask" "F.Paste")
			(net "PVDD18_S5_P0")
		)
	)
)
